(kicad_pcb
	(version 20260206)
	(generator "pcbnew")
	(generator_version "10.0")
	(general
		(thickness 1.6)
		(legacy_teardrops no)
	)
	(paper "A4")
	(title_block
		(title "03242023_DA0F0TMBIJ0_F0T_Motherboard_J_brd_V01_OCP.brd")
		(comment 1 "Grand Teton / footprints 367-373 of 6105")
	)
	(layers
		(0 "F.Cu" signal "TOP")
		(4 "In1.Cu" signal "GND")
		(6 "In2.Cu" signal "IN1")
		(8 "In3.Cu" signal "GND1")
		(10 "In4.Cu" signal "IN2")
		(12 "In5.Cu" signal "GND2")
		(14 "In6.Cu" signal "IN3")
		(16 "In7.Cu" signal "GND3")
		(18 "In8.Cu" signal "VCC")
		(20 "In9.Cu" signal "VCC1")
		(22 "In10.Cu" signal "GND4")
		(24 "In11.Cu" signal "IN4")
		(26 "In12.Cu" signal "GND5")
		(28 "In13.Cu" signal "IN5")
		(30 "In14.Cu" signal "GND6")
		(32 "In15.Cu" signal "IN6")
		(34 "In16.Cu" signal "GND7")
		(2 "B.Cu" signal "BOTTOM")
		(9 "F.Adhes" user "F.Adhesive")
		(11 "B.Adhes" user "B.Adhesive")
		(13 "F.Paste" user "Package Geometry/Pastemask Top")
		(15 "B.Paste" user "Package Geometry/Pastemask Bottom")
		(5 "F.SilkS" user "Ref Des/Silkscreen Top")
		(7 "B.SilkS" user "Ref Des/Silkscreen Bottom")
		(1 "F.Mask" user "Board Geometry/Soldermask Top")
		(3 "B.Mask" user "Board Geometry/Soldermask Bottom")
		(17 "Dwgs.User" user "User.Drawings")
		(19 "Cmts.User" user "User.Comments")
		(21 "Eco1.User" user "User.Eco1")
		(23 "Eco2.User" user "User.Eco2")
		(25 "Edge.Cuts" user "Board Geometry/Outline")
		(27 "Margin" user)
		(31 "F.CrtYd" user "Package Geometry/Place Bound Top")
		(29 "B.CrtYd" user "Package Geometry/Place Bound Bottom")
		(35 "F.Fab" user "Ref Des/Assembly Top")
		(33 "B.Fab" user "Ref Des/Assembly Bottom")
	)
	(footprint ""
		(layer "F.Cu")
		(at 281.758898 -424.54576 -90)
		(property "Reference" "R4669"
			(at 0 0 270)
			(layer "F.SilkS")
			(hide yes)
			(effects
				(font
					(size 1.27 1.27)
				)
			)
		)
		(property "Value" ""
			(at 0 0 270)
			(layer "F.Fab")
			(effects
				(font
					(size 1.27 1.27)
				)
			)
		)
		(duplicate_pad_numbers_are_jumpers no)
		(fp_line
			(start -0.7874 0.4064)
			(end -0.7874 -0.4064)
			(stroke
				(width 0.1524)
				(type default)
			)
			(layer "F.SilkS")
		)
		(fp_line
			(start 0.7874 0.4064)
			(end -0.7874 0.4064)
			(stroke
				(width 0.1524)
				(type default)
			)
			(layer "F.SilkS")
		)
		(fp_line
			(start -0.7874 -0.4064)
			(end 0.7874 -0.4064)
			(stroke
				(width 0.1524)
				(type default)
			)
			(layer "F.SilkS")
		)
		(fp_line
			(start 0.7874 -0.4064)
			(end 0.7874 0.4064)
			(stroke
				(width 0.1524)
				(type default)
			)
			(layer "F.SilkS")
		)
		(fp_line
			(start -0.67945 0.3048)
			(end -0.67945 -0.305054)
			(stroke
				(width 0.1)
				(type default)
			)
			(layer "F.Fab")
		)
		(fp_line
			(start -0.12065 0.3048)
			(end -0.67945 0.3048)
			(stroke
				(width 0.1)
				(type default)
			)
			(layer "F.Fab")
		)
		(fp_line
			(start 0.120396 0.3048)
			(end 0.120396 0.2794)
			(stroke
				(width 0.1)
				(type default)
			)
			(layer "F.Fab")
		)
		(fp_line
			(start 0.67945 0.3048)
			(end 0.120396 0.3048)
			(stroke
				(width 0.1)
				(type default)
			)
			(layer "F.Fab")
		)
		(fp_line
			(start -0.12065 0.2794)
			(end -0.12065 0.3048)
			(stroke
				(width 0.1)
				(type default)
			)
			(layer "F.Fab")
		)
		(fp_line
			(start 0.120396 0.2794)
			(end -0.12065 0.2794)
			(stroke
				(width 0.1)
				(type default)
			)
			(layer "F.Fab")
		)
		(fp_line
			(start -0.12065 -0.2794)
			(end 0.12065 -0.2794)
			(stroke
				(width 0.1)
				(type default)
			)
			(layer "F.Fab")
		)
		(fp_line
			(start 0.12065 -0.2794)
			(end 0.12065 -0.3048)
			(stroke
				(width 0.1)
				(type default)
			)
			(layer "F.Fab")
		)
		(fp_line
			(start 0.12065 -0.3048)
			(end 0.67945 -0.3048)
			(stroke
				(width 0.1)
				(type default)
			)
			(layer "F.Fab")
		)
		(fp_line
			(start 0.67945 -0.3048)
			(end 0.67945 0.3048)
			(stroke
				(width 0.1)
				(type default)
			)
			(layer "F.Fab")
		)
		(fp_line
			(start -0.67945 -0.305054)
			(end -0.12065 -0.305054)
			(stroke
				(width 0.1)
				(type default)
			)
			(layer "F.Fab")
		)
		(fp_line
			(start -0.12065 -0.305054)
			(end -0.12065 -0.2794)
			(stroke
				(width 0.1)
				(type default)
			)
			(layer "F.Fab")
		)
		(pad "1" smd circle
			(at -0.40005 0 270)
			(size 0 0)
			(layers "F.Cu" "F.Mask" "F.Paste")
			(net "HSC_CSOUT")
		)
		(pad "2" smd circle
			(at 0.40005 0 270)
			(size 0 0)
			(layers "F.Cu" "F.Mask" "F.Paste")
			(net "A_HSC_HIGH")
		)
	)
	(footprint ""
		(layer "F.Cu")
		(at 373.65813 -408.517344 -90)
		(property "Reference" "C871"
			(at 0 0 270)
			(layer "F.SilkS")
			(hide yes)
			(effects
				(font
					(size 1.27 1.27)
				)
			)
		)
		(property "Value" ""
			(at 0 0 270)
			(layer "F.Fab")
			(effects
				(font
					(size 1.27 1.27)
				)
			)
		)
		(duplicate_pad_numbers_are_jumpers no)
		(fp_line
			(start -0.299974 0.150114)
			(end -0.299974 -0.150114)
			(stroke
				(width 0.1)
				(type default)
			)
			(layer "F.Fab")
		)
		(fp_line
			(start 0.299974 0.150114)
			(end -0.299974 0.150114)
			(stroke
				(width 0.1)
				(type default)
			)
			(layer "F.Fab")
		)
		(fp_line
			(start -0.299974 -0.150114)
			(end 0.299974 -0.150114)
			(stroke
				(width 0.1)
				(type default)
			)
			(layer "F.Fab")
		)
		(fp_line
			(start 0.299974 -0.150114)
			(end 0.299974 0.150114)
			(stroke
				(width 0.1)
				(type default)
			)
			(layer "F.Fab")
		)
		(pad "1" smd rect
			(at -0.2667 0 270)
			(size 0.3048 0.381)
			(layers "F.Cu" "F.Mask" "F.Paste")
			(net "P5E_CPU0_PE3_TX_C_DP<15>")
		)
		(pad "2" smd rect
			(at 0.2667 0 270)
			(size 0.3048 0.381)
			(layers "F.Cu" "F.Mask" "F.Paste")
			(net "P5E_CPU0_PE3_TX_DP<15>")
		)
	)
	(footprint ""
		(layer "F.Cu")
		(at 123.994926 -119.810784 -90)
		(property "Reference" "R4037"
			(at 0 0 270)
			(layer "F.SilkS")
			(hide yes)
			(effects
				(font
					(size 1.27 1.27)
				)
			)
		)
		(property "Value" ""
			(at 0 0 270)
			(layer "F.Fab")
			(effects
				(font
					(size 1.27 1.27)
				)
			)
		)
		(duplicate_pad_numbers_are_jumpers no)
		(fp_line
			(start -0.7874 0.4064)
			(end -0.7874 -0.4064)
			(stroke
				(width 0.1524)
				(type default)
			)
			(layer "F.SilkS")
		)
		(fp_line
			(start 0.7874 0.4064)
			(end -0.7874 0.4064)
			(stroke
				(width 0.1524)
				(type default)
			)
			(layer "F.SilkS")
		)
		(fp_line
			(start -0.7874 -0.4064)
			(end 0.7874 -0.4064)
			(stroke
				(width 0.1524)
				(type default)
			)
			(layer "F.SilkS")
		)
		(fp_line
			(start 0.7874 -0.4064)
			(end 0.7874 0.4064)
			(stroke
				(width 0.1524)
				(type default)
			)
			(layer "F.SilkS")
		)
		(fp_line
			(start -0.67945 0.3048)
			(end -0.67945 -0.305054)
			(stroke
				(width 0.1)
				(type default)
			)
			(layer "F.Fab")
		)
		(fp_line
			(start -0.12065 0.3048)
			(end -0.67945 0.3048)
			(stroke
				(width 0.1)
				(type default)
			)
			(layer "F.Fab")
		)
		(fp_line
			(start 0.120396 0.3048)
			(end 0.120396 0.2794)
			(stroke
				(width 0.1)
				(type default)
			)
			(layer "F.Fab")
		)
		(fp_line
			(start 0.67945 0.3048)
			(end 0.120396 0.3048)
			(stroke
				(width 0.1)
				(type default)
			)
			(layer "F.Fab")
		)
		(fp_line
			(start -0.12065 0.2794)
			(end -0.12065 0.3048)
			(stroke
				(width 0.1)
				(type default)
			)
			(layer "F.Fab")
		)
		(fp_line
			(start 0.120396 0.2794)
			(end -0.12065 0.2794)
			(stroke
				(width 0.1)
				(type default)
			)
			(layer "F.Fab")
		)
		(fp_line
			(start -0.12065 -0.2794)
			(end 0.12065 -0.2794)
			(stroke
				(width 0.1)
				(type default)
			)
			(layer "F.Fab")
		)
		(fp_line
			(start 0.12065 -0.2794)
			(end 0.12065 -0.3048)
			(stroke
				(width 0.1)
				(type default)
			)
			(layer "F.Fab")
		)
		(fp_line
			(start 0.12065 -0.3048)
			(end 0.67945 -0.3048)
			(stroke
				(width 0.1)
				(type default)
			)
			(layer "F.Fab")
		)
		(fp_line
			(start 0.67945 -0.3048)
			(end 0.67945 0.3048)
			(stroke
				(width 0.1)
				(type default)
			)
			(layer "F.Fab")
		)
		(fp_line
			(start -0.67945 -0.305054)
			(end -0.12065 -0.305054)
			(stroke
				(width 0.1)
				(type default)
			)
			(layer "F.Fab")
		)
		(fp_line
			(start -0.12065 -0.305054)
			(end -0.12065 -0.2794)
			(stroke
				(width 0.1)
				(type default)
			)
			(layer "F.Fab")
		)
		(pad "1" smd circle
			(at -0.40005 0 270)
			(size 0 0)
			(layers "F.Cu" "F.Mask" "F.Paste")
			(net "P3V3_AUX")
		)
		(pad "2" smd circle
			(at 0.40005 0 270)
			(size 0 0)
			(layers "F.Cu" "F.Mask" "F.Paste")
			(net "P0V62_CPU1_RST_DDR_VREF")
		)
	)
	(footprint ""
		(layer "F.Cu")
		(at 362.89488 -294.01008)
		(property "Reference" "C101"
			(at 0 0 0)
			(layer "F.SilkS")
			(hide yes)
			(effects
				(font
					(size 1.27 1.27)
				)
			)
		)
		(property "Value" ""
			(at 0 0 0)
			(layer "F.Fab")
			(effects
				(font
					(size 1.27 1.27)
				)
			)
		)
		(duplicate_pad_numbers_are_jumpers no)
		(fp_line
			(start -1.524 -0.762)
			(end 1.524 -0.762)
			(stroke
				(width 0.1524)
				(type default)
			)
			(layer "F.SilkS")
		)
		(fp_line
			(start -1.524 0.762)
			(end -1.524 -0.762)
			(stroke
				(width 0.1524)
				(type default)
			)
			(layer "F.SilkS")
		)
		(fp_line
			(start 1.524 -0.762)
			(end 1.524 0.762)
			(stroke
				(width 0.1524)
				(type default)
			)
			(layer "F.SilkS")
		)
		(fp_line
			(start 1.524 0.762)
			(end -1.524 0.762)
			(stroke
				(width 0.1524)
				(type default)
			)
			(layer "F.SilkS")
		)
		(fp_line
			(start -1.1049 -0.724916)
			(end -1.1049 0.724916)
			(stroke
				(width 0.1)
				(type default)
			)
			(layer "F.Fab")
		)
		(fp_line
			(start -1.1049 0.724916)
			(end 1.1049 0.724916)
			(stroke
				(width 0.1)
				(type default)
			)
			(layer "F.Fab")
		)
		(fp_line
			(start 1.1049 -0.724916)
			(end -1.1049 -0.724916)
			(stroke
				(width 0.1)
				(type default)
			)
			(layer "F.Fab")
		)
		(fp_line
			(start 1.1049 0.724916)
			(end 1.1049 -0.724916)
			(stroke
				(width 0.1)
				(type default)
			)
			(layer "F.Fab")
		)
		(pad "1" smd rect
			(at -0.889 0 180)
			(size 1.016 1.27)
			(layers "F.Cu" "F.Mask" "F.Paste")
			(net "PVCCIN_CPU0")
		)
		(pad "2" smd rect
			(at 0.889 0 180)
			(size 1.016 1.27)
			(layers "F.Cu" "F.Mask" "F.Paste")
			(net "GND")
		)
	)
	(footprint ""
		(layer "F.Cu")
		(at 244.128798 -50.126646 90)
		(property "Reference" "C1278"
			(at 0 0 90)
			(layer "F.SilkS")
			(hide yes)
			(effects
				(font
					(size 1.27 1.27)
				)
			)
		)
		(property "Value" ""
			(at 0 0 90)
			(layer "F.Fab")
			(effects
				(font
					(size 1.27 1.27)
				)
			)
		)
		(duplicate_pad_numbers_are_jumpers no)
		(fp_line
			(start 0.7874 -0.4064)
			(end 0.7874 0.4064)
			(stroke
				(width 0.1524)
				(type default)
			)
			(layer "F.SilkS")
		)
		(fp_line
			(start -0.7874 -0.4064)
			(end 0.7874 -0.4064)
			(stroke
				(width 0.1524)
				(type default)
			)
			(layer "F.SilkS")
		)
		(fp_line
			(start 0.7874 0.4064)
			(end -0.7874 0.4064)
			(stroke
				(width 0.1524)
				(type default)
			)
			(layer "F.SilkS")
		)
		(fp_line
			(start -0.7874 0.4064)
			(end -0.7874 -0.4064)
			(stroke
				(width 0.1524)
				(type default)
			)
			(layer "F.SilkS")
		)
		(fp_line
			(start -0.12065 -0.305054)
			(end -0.12065 -0.2794)
			(stroke
				(width 0.1)
				(type default)
			)
			(layer "F.Fab")
		)
		(fp_line
			(start -0.67945 -0.305054)
			(end -0.12065 -0.305054)
			(stroke
				(width 0.1)
				(type default)
			)
			(layer "F.Fab")
		)
		(fp_line
			(start 0.67945 -0.3048)
			(end 0.67945 0.3048)
			(stroke
				(width 0.1)
				(type default)
			)
			(layer "F.Fab")
		)
		(fp_line
			(start 0.12065 -0.3048)
			(end 0.67945 -0.3048)
			(stroke
				(width 0.1)
				(type default)
			)
			(layer "F.Fab")
		)
		(fp_line
			(start 0.12065 -0.2794)
			(end 0.12065 -0.3048)
			(stroke
				(width 0.1)
				(type default)
			)
			(layer "F.Fab")
		)
		(fp_line
			(start -0.12065 -0.2794)
			(end 0.12065 -0.2794)
			(stroke
				(width 0.1)
				(type default)
			)
			(layer "F.Fab")
		)
		(fp_line
			(start 0.120396 0.2794)
			(end -0.12065 0.2794)
			(stroke
				(width 0.1)
				(type default)
			)
			(layer "F.Fab")
		)
		(fp_line
			(start -0.12065 0.2794)
			(end -0.12065 0.3048)
			(stroke
				(width 0.1)
				(type default)
			)
			(layer "F.Fab")
		)
		(fp_line
			(start 0.67945 0.3048)
			(end 0.120396 0.3048)
			(stroke
				(width 0.1)
				(type default)
			)
			(layer "F.Fab")
		)
		(fp_line
			(start 0.120396 0.3048)
			(end 0.120396 0.2794)
			(stroke
				(width 0.1)
				(type default)
			)
			(layer "F.Fab")
		)
		(fp_line
			(start -0.12065 0.3048)
			(end -0.67945 0.3048)
			(stroke
				(width 0.1)
				(type default)
			)
			(layer "F.Fab")
		)
		(fp_line
			(start -0.67945 0.3048)
			(end -0.67945 -0.305054)
			(stroke
				(width 0.1)
				(type default)
			)
			(layer "F.Fab")
		)
		(pad "1" smd circle
			(at -0.40005 0 90)
			(size 0 0)
			(layers "F.Cu" "F.Mask" "F.Paste")
			(net "P12V_E1S_0")
		)
		(pad "2" smd circle
			(at 0.40005 0 90)
			(size 0 0)
			(layers "F.Cu" "F.Mask" "F.Paste")
			(net "GND")
		)
	)
	(footprint ""
		(layer "F.Cu")
		(at 250.77039 -53.424582 90)
		(property "Reference" "PC2205"
			(at 0 0 90)
			(layer "F.SilkS")
			(hide yes)
			(effects
				(font
					(size 1.27 1.27)
				)
			)
		)
		(property "Value" ""
			(at 0 0 90)
			(layer "F.Fab")
			(effects
				(font
					(size 1.27 1.27)
				)
			)
		)
		(duplicate_pad_numbers_are_jumpers no)
		(fp_line
			(start 1.2954 -0.5842)
			(end 1.2954 0.5842)
			(stroke
				(width 0.1524)
				(type default)
			)
			(layer "F.SilkS")
		)
		(fp_line
			(start 0 -0.5842)
			(end 0 0.5842)
			(stroke
				(width 0.1524)
				(type default)
			)
			(layer "F.SilkS")
		)
		(fp_line
			(start -1.2954 -0.5842)
			(end 1.2954 -0.5842)
			(stroke
				(width 0.1524)
				(type default)
			)
			(layer "F.SilkS")
		)
		(fp_line
			(start 1.2954 0.5842)
			(end -1.2954 0.5842)
			(stroke
				(width 0.1524)
				(type default)
			)
			(layer "F.SilkS")
		)
		(fp_line
			(start -1.2954 0.5842)
			(end -1.2954 -0.5842)
			(stroke
				(width 0.1524)
				(type default)
			)
			(layer "F.SilkS")
		)
		(fp_line
			(start 0.8636 -0.4572)
			(end 0.8636 -0.4064)
			(stroke
				(width 0.1)
				(type default)
			)
			(layer "F.Fab")
		)
		(fp_line
			(start -0.8636 -0.4572)
			(end 0.8636 -0.4572)
			(stroke
				(width 0.1)
				(type default)
			)
			(layer "F.Fab")
		)
		(fp_line
			(start 1.1938 -0.4064)
			(end 1.1938 0.4064)
			(stroke
				(width 0.1)
				(type default)
			)
			(layer "F.Fab")
		)
		(fp_line
			(start 0.8636 -0.4064)
			(end 1.1938 -0.4064)
			(stroke
				(width 0.1)
				(type default)
			)
			(layer "F.Fab")
		)
		(fp_line
			(start -0.8636 -0.4064)
			(end -0.8636 -0.4572)
			(stroke
				(width 0.1)
				(type default)
			)
			(layer "F.Fab")
		)
		(fp_line
			(start -1.1938 -0.4064)
			(end -0.8636 -0.4064)
			(stroke
				(width 0.1)
				(type default)
			)
			(layer "F.Fab")
		)
		(fp_line
			(start 1.1938 0.4064)
			(end 0.8636 0.4064)
			(stroke
				(width 0.1)
				(type default)
			)
			(layer "F.Fab")
		)
		(fp_line
			(start 0.8636 0.4064)
			(end 0.8636 0.4572)
			(stroke
				(width 0.1)
				(type default)
			)
			(layer "F.Fab")
		)
		(fp_line
			(start -0.8636 0.4064)
			(end -1.1938 0.4064)
			(stroke
				(width 0.1)
				(type default)
			)
			(layer "F.Fab")
		)
		(fp_line
			(start -1.1938 0.4064)
			(end -1.1938 -0.4064)
			(stroke
				(width 0.1)
				(type default)
			)
			(layer "F.Fab")
		)
		(fp_line
			(start 0.8636 0.4572)
			(end -0.8636 0.4572)
			(stroke
				(width 0.1)
				(type default)
			)
			(layer "F.Fab")
		)
		(fp_line
			(start -0.8636 0.4572)
			(end -0.8636 0.4064)
			(stroke
				(width 0.1)
				(type default)
			)
			(layer "F.Fab")
		)
		(pad "1" smd rect
			(at -0.7366 0)
			(size 0.7112 0.8128)
			(layers "F.Cu" "F.Mask" "F.Paste")
			(net "P12V_E1S_AVIN_PD_0")
		)
		(pad "2" smd rect
			(at 0.7366 0)
			(size 0.7112 0.8128)
			(layers "F.Cu" "F.Mask" "F.Paste")
			(net "GND")
		)
	)
	(footprint ""
		(layer "F.Cu")
		(at 409.50261 -408.517344 -90)
		(property "Reference" "C894"
			(at 0 0 270)
			(layer "F.SilkS")
			(hide yes)
			(effects
				(font
					(size 1.27 1.27)
				)
			)
		)
		(property "Value" ""
			(at 0 0 270)
			(layer "F.Fab")
			(effects
				(font
					(size 1.27 1.27)
				)
			)
		)
		(duplicate_pad_numbers_are_jumpers no)
		(fp_line
			(start -0.299974 0.150114)
			(end -0.299974 -0.150114)
			(stroke
				(width 0.1)
				(type default)
			)
			(layer "F.Fab")
		)
		(fp_line
			(start 0.299974 0.150114)
			(end -0.299974 0.150114)
			(stroke
				(width 0.1)
				(type default)
			)
			(layer "F.Fab")
		)
		(fp_line
			(start -0.299974 -0.150114)
			(end 0.299974 -0.150114)
			(stroke
				(width 0.1)
				(type default)
			)
			(layer "F.Fab")
		)
		(fp_line
			(start 0.299974 -0.150114)
			(end 0.299974 0.150114)
			(stroke
				(width 0.1)
				(type default)
			)
			(layer "F.Fab")
		)
		(pad "1" smd rect
			(at -0.2667 0 270)
			(size 0.3048 0.381)
			(layers "F.Cu" "F.Mask" "F.Paste")
			(net "P5E_CPU0_PE3_TX_C_DN<3>")
		)
		(pad "2" smd rect
			(at 0.2667 0 270)
			(size 0.3048 0.381)
			(layers "F.Cu" "F.Mask" "F.Paste")
			(net "P5E_CPU0_PE3_TX_DN<3>")
		)
	)
)
